# ZAIUS-MB-PVT-X04-BOM_X31_20180131_Final.xls.xlsx — Single-Sole Source Parts List (bom)
| FOXCONN TECHNOLOGY GROUP |  |  |  |  |  |  |  |  |  |  |  |  |  |  |  |  |  |
| BILL OF MATERIAL |  |  |  |  |  |  |  |  |  |  |  |  |  |  |  |  |  |
| REV OF  BOM | X31 | CUSTOMER | <name> |  | CUSTOMER P/N |  | PWA P/N： | PWA DESCRIPTION |  |  | PRODUCT CODE |  |  | PWA REV | X04 | DATE | 43131 |
| Sourcing (Single or Sole | Critical Commodity (Y or N) | Component Class (1, 2, other) | Customer PSL (Y/N) | Item Number | Foxconn P/N | Customer P/N | Part Description | Mfr. 1 | Mfr Part # 1 | Proposed Mfr. 2 | Proposed Mfr. 2 PN | Qty | RoHS Status | Location | 2nd Source Qual Build: | Customer Comments | ODM Comments |
| Single |  |  |  | 1 | 0101FBQ00-000-G |  | PCB,Zaius-MB PVT-X04,OSP,Gre,22L,22.20*13.00,G | GOLD CIRCUIT ELECTRONICS LTD. | 0101FBQ00-000-G |  |  | 1 | G | PCB |  |  |  |
| Sole | Y | ND | Y(5) | 5 | 62120BE00-015-G |  | SP-CAP,100uF,+/-20%,16V,105℃,G,SMD2816,ESR<=12mOhm | MURATA ELEC. NORTH AMERICA | ECASD91C107M012K01 |  |  | 10 | G | CE21,CE22,CE23,CE24,CE25,CE26,CE27,CE28,CE29,CE30 |  |  |  |
| Sole | ND |  | Y(3) | 13 | 62012P100-015-G |  | CAP,2.2uF,+/-20%,X7S,10V,G,SMD0402 | MURATA ELEC. NORTH AMERICA | GRM155C71A225M |  |  | 28 | G | PSTC5,PSLC5,PSFC5,PSEC5,PSDC5,PQPC5,PFRC5,PEEC5,PEDC5,C46,C63,C69,C79,C142,C144,C157,C167,C226,C234,C774,C781,C785,C813,C856,C864,C873,C883,C2011 |  |  |  |
| Single | Y | 2 | Y(3) | 34 | 620107600-015-G | - | CAP,27pF,+/-5%,NPO(C0G),50V,G,SMD0402 | MURATA ELEC. NORTH AMERICA | GRM1555C1H270J |  |  | 2 | G | C1707,C1708 |  |  |  |
| Sole | ND | ND | Y(1) | 43 | 62012TW00-015-G | - | CAP,470nF,+/-10%,X7R,16V,G,SMD0402 | MURATA ELEC. NORTH AMERICA | GRM155R71C474KE01D |  |  | 2 | G | C2081,C2082 |  |  |  |
| Single | Y |  | N | 54 | 52180BC00-223-G |  | DIODE,Array-TVS,ESD8004MUTAG,G,UDFN-10,SMD | ON SEMICONDUCTOR CORP | ESD8004MUTAG |  |  | 1 | G | ED1 |  |  |  |
| Sole | ND |  | Y(1) | 59 | 730100400-086-G |  | Fuse,Very fast acting,3A,32V,G,SMD0603 | LITTELFUSE FAR EAST PTE LTD | 0467003.NR |  |  | 2 | G | FS2,FS3 |  |  |  |
| Sole | N |  | Y(1) | 63 | 730102000-086-G |  | Fuse,Fast acting,24V,10A,G,SMD1206 | LITTELFUSE FAR EAST PTE LTD | 0501010.WR |  |  | 1 | G | FS22 |  |  |  |
| Sole | ND |  | Y(1) | 64 | 730108F00-086-G |  | Fuse,Fast acting,500V,30A,G,SMD | LITTELFUSE FAR EAST PTE LTD | 0505030.MXP |  |  | 2 | G | FS27,FS28 |  |  |  |
| Single | ND | ND | Y(1) | 66 | 730101C00-086-G |  | Fuse,Slow blow,125V,30A,G,SMD | LITTELFUSE FAR EAST PTE LTD | 0456030.ER |  |  | 1 | G | FS30 |  |  |  |
| Sole | ND |  | N | 72 | 52113AY00-289-G |  | LED,Red,LTL-42NEW8DH184P,5V,20mA,G,DIP-2 | LITE-ON TECHNOLOGY CORPORATION | LTL-42NEW8DH184P |  |  | 2 | G | LED8,LED9 |  |  |  |
| Single | ND |  | N | 73 | 52113B000-289-G |  | LED,Yellow,LTL-42NSV8DH184P,5V,20mA,G,DIP-2 | LITE-ON TECHNOLOGY CORPORATION | LTL-42NSV8DH184P |  |  | 2 | G | LED10,LED14 |  |  |  |
| Single | ND |  | N | 74 | 52113AW00-289-G |  | LED,Green,LTL-42NGY8DH184P,5V,20mA,G,DIP-2 | LITE-ON TECHNOLOGY CORPORATION | LTL-42NGY8DH184P |  |  | 2 | G | LED11,LED12 |  |  |  |
| Single | ND |  | N | 75 | 52113B100-289-G |  | LED,Blue,LTL42TB6NH184P,5V,30mA,G,DIP-2 | LITE-ON TECHNOLOGY CORPORATION | LTL42TB6NH184P |  |  | 1 | G | LED13 |  |  |  |
| Sole | N |  | N | 76 | 52110FE00-289-G |  | LED,Red,LTST-C190KRKT,2.4V,30mA,G,SMD0603 | LITE-ON TECHNOLOGY CORPORATION | LTST-C190KRKT |  |  | 3 | G | LED63,LED64,LED65 |  |  |  |
| Single | ND |  | ND | 85 | 62111U700-024-G |  | ECAP,68uF,+/-20%,100V,105C,320mOhm,G,SMD12.5*13.5 | PANASONIC INDUSTRIAL CO.,LTD. | EEEFK2A680AQ |  |  | 6 | G | PSUCE1,PBACE1,PAACE1,PSUCE2,PBACE2,PAACE2 |  |  |  |
| Sole | N |  | Y(1) | 86 | 62111QQ00-019-G |  | ECAP,82uF,+/-20%,100V,105C,G,SMD12.5*13.5,ESR<=280mOhm | NICHICON CORPORATION | UCZ2A820MNQ1MS |  |  | 8 | G | PBMCE1,PAMCE1,PBFCE2,PBECE2,PAFCE2,PAECE2,PBACE3,PAACE3 |  |  |  |
| Single | N |  | Y(3) | 87 | 62120ER01-024-G |  | ECAP,SPEA,470uF,+/-20%,2.5V,105C,G,SMD2816,ESR<=3mOhm | PANASONIC INDUSTRIAL CO.,LTD. | EEFGX0E471R |  |  | 50 | G | PBNCE1,PANCE1,PBNCE2,PANCE2,PBECE3,PALCE3,PAFCE3,PAECE3,PBMCE4,PBFCE4,PBECE4,PBACE4,PAMCE4,PALCE4,PAFCE4,PAECE4,PAACE4,PBMCE5,PBFCE5,PBECE5,PBACE5,PAMCE5,PAFCE5,PAECE5,PAACE5,PBMCE6,PBFCE6,PBECE6,PBACE6,PAMCE6,PAFCE6,PAECE6,PAACE6,PBMCE7,PBLCE7,PBFCE7,PBACE7,PAMCE7,PAACE7,PBLCE8,PBACE8,PAACE8,PBACE9,PAACE9,PBACE10,PAACE10,PBACE11,PAACE11,PBACE12,PAACE12 |  |  |  |
| Single | Y | 2 | Y(3) | 91 | 620102T00-015-G | - | CAP,150pF,+/-5%,NPO(C0G),50V,G,SMD0402 | MURATA ELEC. NORTH AMERICA | GRM1555C1H151J |  |  | 8 | G | PBMC7,PBFC7,PBEC7,PBAC7,PAMC7,PAFC7,PAEC7,PAAC7 |  |  |  |
| Single | ND | ND | Y(1) | 95 | 62011DA00-015-G | - | CAP,1uF,+/-10%,X7R,100V,G,SMD1206 | MURATA ELEC. NORTH AMERICA | GRM31CR72A105K |  |  | 6 | G | PBMC27,PBAC27,PAMC27,PAAC27,PBAC111,PAAC111 |  |  |  |
| Sole | ND |  | N | 100 | 52030TQ00-237-G |  | Diode,Schottky,BAS40-06-7-F,40V,200mA,G,SOT-23-3,SMD | DIODES INCORPORATION | BAS40-06-7-F |  |  | 8 | G | PBMD3,PBFD3,PBED3,PBAD3,PAMD3,PAFD3,PAED3,PAAD3 |  |  |  |
| Sole | ND |  | N | 103 | 63035R700-57M-G |  | IND,375nH@1MHz,+/-5%,16A,1.15mOhm,SHLD,G,SMD | Eaton Corporation | CTX01-19603-R |  |  | 2 | G | PBAL2,PAAL2 |  |  |  |
| Single | ND | ND | ND | 125 | 610100C00-017-G | - | RES,15kOhm,+/-1%,1/10W,G,SMD0603 | KOA SPEER ELECTRONICS, INC. | RK73H1JTTD1502F |  |  | 2 | G | PBAR80,PAAR80 |  |  |  |
| Single | ND | ND | Y(1) | 143 | 32040FG00-183-G |  | IC,Current Sensor,INA193AIDBVR,G,SOT23-5,SMD | TEXAS INSTRUMENTS | INA193AIDBVR |  |  | 8 | G | PBMU2,PBFU2,PBEU2,PBAU2,PAMU2,PAFU2,PAEU2,PAAU2 |  |  |  |
| Sole | N |  | N | 144 | 32014E200-53N-G |  | IC,Regulator,PI3753-00-LGIZ,ADJ,10.3A,G,LGA-108,SMD | Vicor Corporation | PI3753-00-LGIZ |  |  | 2 | G | PBAU3,PAAU3 |  |  |  |
| Sole | N |  | N | 145 | 880302200-53N-G |  | Converter,input 0V~60V,185W,G,VTM48MP012T130AA0 | Vicor Corporation | VTM48MP012T130AA0 |  |  | 4 | G | PBAU4,PAAU4,PBAU6,PAAU6 |  |  |  |
| Sole | N |  | Y(3) | 146 | 32031MS00-183-G |  | IC,Operation Amplifier,OPA2365AIDR,G,SOIC-8,SMD | TEXAS INSTRUMENTS | OPA2365AIDR |  |  | 8 | G | PBMU5,PBFU5,PBEU5,PAMU5,PAFU5,PAEU5,PBAU7,PAAU7 |  |  |  |
| Single | ND | ND | Y(3) | 147 | 620108600-015-G | - | CAP,180pF,+/-5%,NPO(C0G),50V,G,SMD0402 | MURATA ELEC. NORTH AMERICA | GRM1555C1H181J |  |  | 4 | G | PBFC4,PBEC4,PAFC4,PAEC4 |  |  |  |
| Single | N |  | Y(4) | 153 | 61100YT00-017-G |  | RES,487 Ohm,+/-0.1%,1/16W,G,SMD0402 | KOA SPEER ELECTRONICS, INC. | RN731ETTP4870B25 |  |  | 4 | G | PBFR34,PBER34,PAFR34,PAER34 |  |  |  |
| Single | ND |  | Y(4) | 155 | 610127L00-017-G |  | RES,215 Ohm,+/-1%,1/16W,G,SMD0402 | KOA SPEER ELECTRONICS, INC. | RK73H1ETTP2150F |  |  | 4 | G | PBFR57,PBER57,PAFR57,PAER57 |  |  |  |
| Single | N | Other | Y(4) | 159 | 610107K00-017-G | - | RES,24.9KOhm,+/-1%,1/10W,G,SMD0603 | KOA SPEER ELECTRONICS, INC. | RK73H1JTTD2492F |  |  | 4 | G | PBER84,PAFR84,PAER84,PBFR85 |  |  |  |
| Sole | N |  | N | 161 | 32014CE00-53N-G |  | IC,Regulator,PI3755-02-LGIZ,ADJ,4A,G,LGA-71,SMD | Vicor Corporation | PI3755-02-LGIZ |  |  | 6 | G | PBMU3,PBFU3,PBEU3,PAMU3,PAFU3,PAEU3 |  |  |  |
| Sole | N | ND | N | 162 | 880302600-53N-G | - | Converter,input 0V~52V,120W,G,VTM48RP015C076AG0 | Vicor Corporation | VTM48RP015C076AG0 |  |  | 4 | G | PBFU4,PBEU4,PAFU4,PAEU4 |  |  |  |
| Sole | N |  | Y(3) | 166 | 62012GG00-015-G |  | CAP,10uF,+/-10%,X7S,25V,G,SMD0805 | MURATA ELEC. NORTH AMERICA | GRM21BC71E106K |  |  | 68 | G | PSTC2,PSLC2,PSFC2,PSEC2,PSDC2,PQPC2,PFRC2,PEEC2,PEDC2,PANC2,PSTC3,PSLC3,PSFC3,PSEC3,PSDC3,PQPC3,PFRC3,PEEC3,PEDC3,PBNC3,PANC3,PBNC4,PANC4,PBNC5,PANC5,PSPC6,PIPC6,PFPC6,PEPC6,PBNC6,PSPC7,PIPC7,PFPC7,PEPC7,PSPC8,PIPC8,PFPC8,PEPC8,PSPC9,PIPC9,PFPC9,PEPC9,PSTC17,PSTC18,PALC38,PALC39,PBLC54,PBLC55,PSPC3004,PIPC3004,PFPC3004,PEPC3004,PSPC3005,PIPC3005,PFPC3005,PEPC3005,PSPC3006,PIPC3006,PFPC3006,PEPC3006,PSPC3007,PIPC3007,PFPC3007,PEPC3007,PSPC3009,PIPC3009,PFPC3009,PEPC3009 |  |  |  |
| Sole | N |  | N | 169 | 320244200-230-G |  | IC,PWM Controller,ISL99227FRZ-T,G,QFN-32,SMD | INTERSIL CORPORATION | ISL99227FRZ-T |  |  | 2 | G | PALU1,PBLU3 |  |  |  |
| Single | Y | 2 | Y(3) | 170 | 62010BH00-015-G | - | CAP,220pF,+/-5%,NPO(C0G),50V,G,SMD0402 | MURATA ELEC. NORTH AMERICA | GRM1555C1H221J |  |  | 2 | G | PBMC4,PAMC4 |  |  |  |
| Single | ND |  | Y(5) | 172 | 61100YW00-017-G |  | RES,316 Ohm,+/-0.1%,1/16W,G,SMD0402 | KOA SPEER ELECTRONICS, INC. | RN731ETTP3160B25 |  |  | 2 | G | PBMR34,PAMR34 |  |  |  |
| Single | ND | ND | Y(4) | 174 | 610119U00-017-G | - | RES,133 Ohm,+/-1%,1/16W,G,SMD0402 | KOA SPEER ELECTRONICS, INC. | RK73H1ETTP1330F |  |  | 2 | G | PBMR57,PAMR57 |  |  |  |
| Single | ND | ND | Y(4) | 176 | 61010A700-017-G | - | RES,30.9KOhm,+/-1%,1/10W,G,SMD0603 | KOA SPEER ELECTRONICS, INC. | RK73H1JTTD3092F |  |  | 2 | G | PBMR77,PAMR77 |  |  |  |
| Single | N | ND | Y(4) | 177 | 61011FU00-017-G |  | RES,115KOhm,+/-1%,1/16W,G,SMD0402 | KOA SPEER ELECTRONICS, INC. | RK73H1ETTP1153F |  |  | 2 | G | PBMR121,PAMR121 |  |  |  |
| Sole | N |  | N | 178 | 880302800-53N-G |  | Converter,input 0V~60V,131W,G,VTM48MP010C105AG0 | Vicor Corporation | VTM48MP010C105AG0 |  |  | 2 | G | PBMU4,PAMU4 |  |  |  |
| Single | ND |  | N | 192 | 10061913-102HLF |  | CONN,PCIE-8X,V/T,Bla,1mm,30u,G,SMD-98 | FCI CONNECTORS HONGKONG LTD. | 10061913-102HLF |  |  | 2 | G | PCIE1,PCIE5 |  |  |  |
| Sole | N |  | Y(3) | 197 | 62012G600-015-G |  | CAP,2.2uF,+/-10%,X7S,25V,G,SMD0603 | MURATA ELEC. NORTH AMERICA | GRM188C71E225K |  |  | 11 | G | PUAC19,PSIC19,PSAC19,PRAC19,PQAC19,PPAC19,PIAC19,PFAC19,PETC19,PERC19,PEAC19 |  |  |  |
| Sole | Y |  | N | 204 | 32012NN00-238-G |  | IC,Regulator,IR3898MTRPBF,6A,1.5MHZ,G,QFN-17,SMD | INTERNATIONAL RECTIFIER | IR3898MTRPBF |  |  | 11 | G | PUAU1,PSIU1,PSAU1,PRAU1,PQAU1,PPAU1,PIAU1,PFAU1,PETU1,PERU1,PEAU1 |  |  |  |
| Sole | ND |  | ND | 210 | 32013PD00-238-G |  | IC,Regulator,IR3883MTRPbF,ADJ,3A,G,QFN-16,SMD | INTERNATIONAL RECTIFIER | IR3883MTRPBF |  |  | 9 | G | PSTU1,PSLU1,PSFU1,PSEU1,PSDU1,PQPU1,PFRU1,PEEU1,PEDU1 |  |  |  |
| Sole | N | Other | Y(1) | 213 | 62120CM00-024-G | - | SPEA CAP,220uF,+10%~-35%,6.3V,105C,G,SMD2816,ESR<=15mOhm | PANASONIC INDUSTRIAL CO.,LTD. | EEFCX0J221YR |  |  | 14 | G | PSRCE3000,PSRCE3001,PSPCE3003,PIPCE3003,PFPCE3003,PEPCE3003,PSPCE3004,PIPCE3004,PFPCE3004,PEPCE3004,PSPCE3005,PIPCE3005,PFPCE3005,PEPCE3005 |  |  |  |
| Sole | ND |  | N | 222 | 32013HH00-238-G |  | IC,Regulator,IR3447MTRPBF,ADJ,25A,G,PQFN-33 | INTERNATIONAL RECTIFIER | IR3447MTRPBF |  |  | 4 | G | PSPU1,PIPU1,PFPU1,PEPU1 |  |  |  |
| Sole | N |  | N | 224 | 62013BP00-015-G |  | CAP,22uF,+/-20%,X6S,25V,G,SMD1206 | MURATA ELEC. NORTH AMERICA | GRM31CC81E226ME11L |  |  | 10 | G | PSIC4,PETC4,PERC4,PSIC5,PETC5,PERC5,PSIC6,PETC6,PERC6,PETC22 |  |  |  |
| Sole | N |  | N | 231 | 62011LT01-015-G |  | CAP,130pF,+/-5%,NPO(C0G),50V,G,SMD0402 | MURATA ELEC. NORTH AMERICA | GRM1555C1H131JA01D |  |  | 1 | G | PETC3 |  |  |  |
| Sole | ND |  | Y(1) | 241 | 620135500-015-G |  | CAP,39nF,+/-10%,X7R,100V,G,SMD0805 | MURATA ELEC. NORTH AMERICA | GRM21BR72A393KA01L |  |  | 1 | G | PHAC18 |  |  |  |
| Sole | N |  | N | 243 | 52030YE00-223-G |  | DIODE,Schottky,MBR5H100MFST1G,100V,5A,G,SO8FL-8,SMD | ON SEMICONDUCTOR CORP | MBR5H100MFST1G |  |  | 1 | G | PHAD2 |  |  |  |
| Single | N |  | N | 247 | 51032D100-237-G |  | MOS N,DMN10H220L-7,100V,1.6A,220m@10V,G,SOT-23-3,SMD | DIODES INCORPORATION | DMN10H220L-7 |  |  | 2 | G | PHAQ5,PHAQ6 |  |  |  |
| Sole | ND |  | ND | 248 | 610601801-32D-G |  | RES,0.5mOhm,+/-1%,2W,G,SMD1225 | Thin Film Technology Corporation | CPA1225R0M50FW-T5 |  |  | 1 | G | PHAR1 |  |  |  |
| Single | ND | ND | Y(4) | 255 | 610113D00-017-G | - | RES,10.5KOhm,+/-1%,1/16W,G,SMD0402 | KOA SPEER ELECTRONICS, INC. | RK73H1ETTP1052F |  |  | 1 | G | PHAR35 |  |  |  |
| Sole | ND |  | Y(1) | 257 | 32023RR00-183-G |  | IC,Power Controller,LM5066IPMHX/NOPB,G,HTSSOP-28,SMD | TEXAS INSTRUMENTS | LM5066IPMHX/NOPB |  |  | 1 | G | PHAU1 |  |  |  |
| Sole | N | ND | Y(3) | 264 | 62011LY01-015-G | - | CAP,160pF,+/-5%,NPO(C0G),50V,G,SMD0402 | MURATA ELEC. NORTH AMERICA | GRM1555C1H161JA01D |  |  | 1 | G | PSIC3 |  |  |  |
| Sole | N |  | N | 267 | 62013BS00-015-G |  | CAP,3nF,+/-10%,X7R,50V,G,SMD0402 | MURATA ELEC. NORTH AMERICA | GRM155R71H302KA01D |  |  | 1 | G | PSPC10 |  |  |  |
| Sole | ND |  | Y(1) | 269 | 62012T500-015-G |  | CAP,22uF,+/-20%,X7S,25V,G,SMD1206 | MURATA ELEC. NORTH AMERICA | GRM31CC71E226ME11L |  |  | 12 | G | PSRC4,PSUC5,PSRC5,PSUC6,PSRC6,PSUC7,PSUC8,PSUC9,PSUC10,PSRC3001,PSRC3002,PSRC3005 |  |  |  |
| Sole | N |  | N | 270 | 62013BQ00-015-G |  | CAP,3.6nF,+/-10%,X7R,50V,G,SMD0402 | MURATA ELEC. NORTH AMERICA | GRM155R71H362KA01D |  |  | 1 | G | PSRC7 |  |  |  |
| Sole | ND |  | N | 278 | 32013FK00-238-G |  | IC,Regulator,IR3846MTRPBF,ADJ,35A,G,PQFN-26,SMD | INTERNATIONAL RECTIFIER | IR3846MTRPBF |  |  | 1 | G | PSRU1 |  |  |  |
| Single | N |  | Y(4) | 282 | 610119C00-017-G |  | RES,130KOhm,+/-1%,1/16W,G,SMD0402 | KOA SPEER ELECTRONICS, INC. | RK73H1ETTP1303F |  |  | 1 | G | PSUR1 |  |  |  |
| Single | ND | ND | Y(4) | 298 | 610102C00-017-G | - | RES,15KOhm,+/-5%,1/16W,G,SMD0402 | KOA SPEER ELECTRONICS, INC. | RK73B1ETTP153J |  |  | 18 | G | R123,R124,R125,R126,R127,R128,R327,R829,R835,R836,R1125,R1513,R1542,R1543,R1544,R1545,R1546,R1547 |  |  |  |
| Single | ND |  | Y(5) | 310 | 61100H601-017-G |  | RES,2KOhm,+/-0.5%,1/16W,G,SMD0402 | KOA SPEER ELECTRONICS, INC. | RN731ETTP2001D25 |  |  | 1 | G | R751 |  |  |  |
| Sole | Y | ND | Y(1) | 351 | 21040M500-283-G | - | IC,BROADCOM,BCM54612EB1KMLG,B1,G,MLP-48,SMD | BROADCOM SINGAPORE PTE LTD. | BCM54612EB1KMLG |  |  | 1 | G | U13 |  |  |  |
| Sole | ND |  | N | 352 | 21012NH00-687-G | - | IC,ASPEED,AST2500A2-GP,A2,G,TFBGA-456,SMD | ASPEED TECHNOLOGY INC | AST2520A2-GP |  |  | 1 | G | U14 |  |  |  |
| Sole | N |  | Y(1) | 355 | 310311G00-183-G |  | IC,Switch,TS3L110RGYR,3V~3.6V,G,VQFN-16,SMD | TEXAS INSTRUMENTS | TS3L110RGYR |  |  | 2 | G | U18,U19 |  |  |  |
| Sole | ND | ND | N | 362 | 32022AL00-223-G | - | IC,Power Controller,NCP380HSNAJAAT1G,G,TSOP-6,SMD | ON SEMICONDUCTOR CORP | NCP380HSNAJAAT1G |  |  | 3 | G | U33,U35,U177 |  |  |  |
| Sole | ND |  | N | 363 | 21081AQ00-426-G |  | IC,RENESAS,uPD720201K8-701-BAC-A,G,QFN-68,SMD | RENESAS TECHNOLOGY AMERICA INC | uPD720201K8-701-BAC-A |  |  | 1 | G | U36 |  |  |  |
| Sole | ND | ND | N | 364 | 41050J100-233-G | - | Flash,MX25L5121EMC-20G,2.7~3.6V,512K,SPI,G,SOP-8,SMD | MACRONIX INTERNATIONAL CO.,LTD. | MX25L5121EMC-20G |  |  | 1 | G | U37 |  |  |  |
| Sole | ND |  | N | 365 | 210826400-183-G |  | IC,TI,TUSB2077APTR,G,LQFP-48,SMD | TEXAS INSTRUMENTS | TUSB2077APTR |  |  | 1 | G | U38 |  |  |  |
| Sole | ND |  | N | 366 | 21081N000-348-G |  | IC,MARVELL,88SE9235A1-NAA2C000,A1,G,QFN-76,SMD | MARVELL SEMICONDUCTOR, INC | 88SE9235A1-NAA2C000[VER.A1] |  |  | 1 | G | U45 |  |  |  |
| Sole | Y |  | N | 369 | 21050P200-031-G |  | IC,NXP,PCF8523TK,G,HVSON-8,SMD | NXP SEMICONDUCTORS | PCF8523TK |  |  | 1 | G | U60 |  |  |  |
| Sole | ND | ND | N | 371 | 21050R500-298-G |  | IC,SILABS,Si5338C-B06799-GMR,G,QFN-24,SMD | Silicon Laboratories Inc. | SI5338C-B06799-GMR |  |  | 1 | G | U62 |  |  |  |
| Sole | ND |  | Y(1) | 372 | 21050P100-217-G |  | IC,IDT,9DBL0452BKILFT,G,VFQFPN-32,SMD | INTEGRATED DEVICE TECHNOLOGY | 9DBL0452BKILFT |  |  | 1 | G | U63 |  |  |  |
| Sole | ND |  | Y(1) | 376 | 320231500-183-G |  | IC,Voltage Sensor,TPS3897ADRYR,G,SON-6,SMD | TEXAS INSTRUMENTS | TPS3897ADRYR |  |  | 1 | G | U84 |  |  |  |
| Sole | ND |  | Y(1) | 377 | 32020LS00-183-G |  | IC,Power Controller,TPS3801K33DCKR,G,SC-70-5,SMD | TEXAS INSTRUMENTS | TPS3801K33DCKR |  |  | 1 | G | U87 |  |  |  |
| Sole | ND |  | Y(3) | 379 | 31050J800-031-G |  | IC,Buffer,PCA9516APW,2.3V~3.6V,G,TSSOP-16,SMD | NXP SEMICONDUCTORS | PCA9516APW |  |  | 4 | G | U92,U93,U94,U95 |  |  |  |
| Sole | N |  | Y(2) | 380 | 32021R100-252-G |  | IC,Power Controller,PI3USB102ZLEX,G,TQFN-10P,SMD | PERICOM SEMICONDUCTOR CORP | PI3USB102ZLEX |  |  | 2 | G | U96,U108 |  |  |  |
| Sole | ND |  | Y(2) | 381 | 31090C800-031-G |  | IC,Transceiver,74AVC4TD245GU,0.8V~3.6V,G,XQFN-16,SMD | NXP SEMICONDUCTORS | 74AVC4TD245GU |  |  | 1 | G | U97 |  |  |  |
| Sole | ND | ND | Y(2) | 383 | 210203M00-031-G | - | IC,NXP,PCA9554PW,G,TSSOP-16,SMD | NXP SEMICONDUCTORS | PCA9554PW |  |  | 2 | G | U99,U100 |  |  |  |
| Sole | ND |  | N | 387 | 21081WR00-031-G |  | IC,NXP,PCA9541APW/01,G,TSSOP-16,SMD | NXP SEMICONDUCTORS | PCA9541APW/01 |  |  | 1 | G | U116 |  |  |  |
| Sole | ND |  | Y(1) | 388 | 311006F00-031-G |  | IC,Translator,PCA9508D,0.9V~5.5V/2.7V~5.5V,G,SO-8,SMD | NXP SEMICONDUCTORS | PCA9508D |  |  | 1 | G | U164 |  |  |  |
| Sole | ND |  | N | 389 | 320242H00-226-G |  | IC,Power Controller,LTC2955CDDB-2#TRMPBF,G,DFN-10,SMD | LINEAR TECHNOLOGY CORPORATION | LTC2955CDDB-2#TRMPBF |  |  | 1 | G | U165 |  |  |  |
| Sole | ND |  | N | 390 | 32050Q900-031-G |  | IC,LED Driver,PCA9551PW,G,TSSOP-16,SMD | NXP SEMICONDUCTORS | PCA9551PW |  |  | 1 | G | U166 |  |  |  |
| Sole | ND |  | Y(1) | 394 | 31010SB00-183-G |  | Logic IC,Gate,ISO1540DR,3V~5.5V,G,SOIC-8,SMD | TEXAS INSTRUMENTS | ISO1540DR |  |  | 1 | G | U175 |  |  |  |
| Sole | ND |  | N | 397 | 71012EC00-162-G |  | XTAL,6MHz,+/-30ppm,20pF,G,SMD | EPSON ELECTRONICS AMERICA,INC. | Q22MA4061164200 |  |  | 1 | G | X4 |  |  |  |
| Sole | ND |  | N | 398 | 71011UL00-107-G |  | XTAL,25MHz,+/-15ppm,16pF,G,SMD | DAISHINKU CORPORATION/DAISHINKU SINGAPORE PTE LTD/KDS | 1ZHY25000BB0A |  |  | 1 | G | X5 |  |  |  |
| Sole | ND |  | N | 400 | 71020SC00-107-G |  | OSC,24MHz,+/-25ppm,3.3V,15pF,G,SMD | DAISHINKU CORPORATION/DAISHINKU SINGAPORE PTE LTD/KDS | 1XSE024000AR40 |  |  | 1 | G | Y1 |  |  |  |
| Sole | ND |  | N | 402 | 710213J00-16G-G |  | OSC,25MHz,+/-1.5ppm,3.3V,15pF,G,SMD | SiTime Corporation | SIT5000AC-3B-33N0-25.000000T |  |  | 1 | G | Y3 |  |  |  |
| Sole | Y |  | N | 404 | 340660600-GRS-G |  | CONN,Header,Battery Holder,Bla,21.3mm,G/F,G,SMD-2 | LOTES CO LTD | AAA-BAT-063-P02_A |  |  | 1 | G | B1 |  |  |  |
| Sole | ND | ND | N | 405 | 2T714BY00-086-G | - | Fuse Clips,10.67mm*7.11mm*7.87mm,G,LITTELFUSE,01220088Z | LITTELFUSE FAR EAST PTE LTD | 01220088Z |  |  | 4 | G | CLIP1,CLIP2,CLIP3,CLIP4 |  |  |  |
| Sole | N | ND | N | 409 | 340692800-309-G | - | CONN,Header,Socket,2X30,V/T,Bla,0.5mm,G/F,G,SMD-60 | SAMTEC INC. | QSH-030-01-F-D-A-K-TR |  |  | 2 | G | J2,J6 |  |  |  |
| Sole | ND |  | N | 410 | 340459T00-GRS-G |  | CONN,I/O,HDMI,V/T,Bla,0.5mm,1u,G,SMD-19 | LOTES CO LTD | AHDM0001-P004A |  |  | 1 | G | J8 |  |  |  |
| Sole | ND | ND | N | 411 | 3406A2A00-309-G | - | CONN,Header,Shrouded,2X4,V/T,1.27mm,15u,G,SMD-8 | SAMTEC INC. | TFM-104-02-L-D-K-TR |  |  | 1 | G | J9 |  |  |  |
| Single | ND |  | N | 412 | 3406B5J00-317-G |  | CONN,Header,Socket,V/T,Bla,2mm,15u,G,DIP-18 | MOLEX INCORPORATED | 79107-7008 |  |  | 1 | G | J10 |  |  |  |
| Single | ND |  | N | 414 | 34064J800-317-G |  | CONN,Header,Socket,2X2,V/T,Bla,2mm,15u,G,DIP-4 | MOLEX INCORPORATED | 79107-7001 |  |  | 1 | G | J13 |  |  |  |
| Sole | ND |  | N | 415 | 34071AW00-245-G |  | CONN,SATA,V/T,Bla,1.27mm,15u,G,DIP-22 | AMPHENOL SHANGHAI CORP. | G16CE41210W3EU |  |  | 1 | G | J14 |  |  |  |
| Sole | ND |  | N | 417 | 34131WS00-G78-G |  | CONN,BTB,Bla,0.8mm,7.87u,G,SMD-120 | FCI CONNECTORS HONGKONG LTD. | 10139781-122402LF |  |  | 1 | G | J16 |  |  |  |
| Sole | ND |  | N | 418 | 34131WT00-G78-G |  | CONN,BTB,Bla,0.8mm,7.87u,G,SMD-80 | FCI CONNECTORS HONGKONG LTD. | 10139781-082402LF |  |  | 1 | G | J17 |  |  |  |
| Single | ND |  | N | 421 | 3406AMV00-317-G |  | CONN,Header,MINFIT,2X4,V/T,Bla,10mm,30u,G,DIP-8 | MOLEX INCORPORATED | 42819-4233 |  |  | 1 | G | J27 |  |  |  |
| Sole | ND |  | N | 422 | 34071BR00-245-G |  | CONN,SAS,V/T,0.6mm,30u,G,SMD-74 | AMPHENOL SHANGHAI CORP. | U10-K074-260T |  |  | 2 | G | J28,J31 |  |  |  |
| Sole | ND |  | N | 423 | 34071BS00-245-G |  | CONN,SAS,V/T,0.6mm,30u,G,SMD-74 | AMPHENOL SHANGHAI CORP. | U10-K074-26BT |  |  | 2 | G | J30,J33 |  |  |  |
| Sole | ND |  | N | 425 | 34051FE00-GRS-G |  | CONN,Modular Jack,USBX2_RJ45,R/A,Bla/Blu,2mm,30u,G,DIP-23 | LOTES CO LTD | AUSBS002-K001C05 |  |  | 1 | G | J99 |  |  |  |
| Sole | ND |  | N | 426 | 3406ARP00-317-G |  | CONN,Header,Power,2X8,V/T,Whi,4.2mm,G,DIP-16 | MOLEX INCORPORATED | 46015-1602 |  |  | 1 | G | J100 |  |  |  |
| Sole | Y |  | N | 428 | 34051HQ00-48U-G |  | CONN,Modular Jack,RJ45X1,R/A,Bla,1.27mm,50u,G,DIP-14 | TRP CONNECTOR B.V. | 1840484-1 |  |  | 1 | G | LAN1 |  |  |  |
| Sole | N |  | N | 431 | ISL68137IRAZ-GG05 |  | IC,PWM Controller,ISL68137IRAZ-T,G,QFN-48,SMD | INTERSIL CORPORATION | ISL68137IRAZ-GG05 |  |  | 8 | G | PBMU1,PBFU1,PBEU1,PBAU1,PAMU1,PAFU1,PAEU1,PAAU1 |  |  |  |
| Sole | N |  | N | 432 | IR38064MTRP=GZS |  | IC,Regulator,IR38064MTRP=GZS,ADJ,35A,G,QFN-26,SMD | INTERNATIONAL RECTIFIER | IR38064MTRP=GZS |  |  | 2 | G | PBNU1,PANU1 |  |  |  |
| Sole | ND |  | N | 434 | 34081GH00-653-G |  | CONN,Switch,tact,Brown,50mA,12V,G,DIP-4 | DIPTRONICS MANUFACTURING INC. | DTSA-644N-Q |  |  | 2 | G | SW3,SW4 |  |  |  |
| Sole |  |  |  | 435 | 340109B00-600-G |  | POWER9 CPU Socket for LGA3899-HYBRID | FOXCONN TECHNOLOGY CO.,LTD. | PE38993-51BC1-1H |  |  | 2 | G | U1,U10 |  |  |  |
| Sole | ND |  | Y(1) | 436 | UCD90160RGCR-C13 |  | IC,Power Controller,UCD90160RGCR,G,VQFN-64,SMD | TEXAS INSTRUMENTS | UCD90160RGCR-C13 |  |  | 1 | G | U5 |  |  |  |
| Sole | ND | ND | N | 437 | 34061E400-GRS-G | - | CONN,Socket,SPI Flash,V/T,Bla,1.27mm,G/F,G,SMD-16 | LOTES CO LTD | ACA-SPI-006-F01 |  |  | 2 | G | U22,U23 |  |  |  |
